# T6G (Grand Teton) — schematic netlist excerpt (pin names and nets, part order shuffled) for the footprints in the layout excerpt that follows; sources: Cadence DE-HDL packaged netlist, KiCad conversion of 04192023_DAF0TMB3IC0_F0TG_MB_C_brd_V02_OCP.brd

C1832  Q_CAP  0.1UF 25V 10% X7R  pkg 0402  page 137 : A = P12V_OCP_V3_2_R ; B = GND
R3667  Q_RES  1K 1% EMPTY  pkg 0402LF  page 257 : A = P3V3_AUX ; B = ADC128_A1

(kicad_pcb
	(version 20260206)
	(generator "pcbnew")
	(generator_version "10.0")
	(general
		(thickness 1.6)
		(legacy_teardrops no)
	)
	(paper "A4")
	(title_block
		(title "04192023_DAF0TMB3IC0_F0TG_MB_C_brd_V02_OCP.brd")
		(comment 1 "Grand Teton / footprints 1783-1784 of 8354")
	)
	(layers
		(0 "F.Cu" signal "TOP")
		(4 "In1.Cu" signal "GND")
		(6 "In2.Cu" signal "IN1")
		(8 "In3.Cu" signal "GND1")
		(10 "In4.Cu" signal "IN2")
		(12 "In5.Cu" signal "GND2")
		(14 "In6.Cu" signal "IN3")
		(16 "In7.Cu" signal "GND3")
		(18 "In8.Cu" signal "VCC")
		(20 "In9.Cu" signal "VCC1")
		(22 "In10.Cu" signal "GND4")
		(24 "In11.Cu" signal "IN4")
		(26 "In12.Cu" signal "GND5")
		(28 "In13.Cu" signal "IN5")
		(30 "In14.Cu" signal "GND6")
		(32 "In15.Cu" signal "IN6")
		(34 "In16.Cu" signal "GND7")
		(2 "B.Cu" signal "BOTTOM")
		(9 "F.Adhes" user "F.Adhesive")
		(11 "B.Adhes" user "B.Adhesive")
		(13 "F.Paste" user "Package Geometry/Pastemask Top")
		(15 "B.Paste" user "Package Geometry/Pastemask Bottom")
		(5 "F.SilkS" user "Ref Des/Silkscreen Top")
		(7 "B.SilkS" user "Ref Des/Silkscreen Bottom")
		(1 "F.Mask" user "Board Geometry/Soldermask Top")
		(3 "B.Mask" user "Board Geometry/Soldermask Bottom")
		(17 "Dwgs.User" user "User.Drawings")
		(19 "Cmts.User" user "User.Comments")
		(21 "Eco1.User" user "User.Eco1")
		(23 "Eco2.User" user "User.Eco2")
		(25 "Edge.Cuts" user "Board Geometry/Outline")
		(27 "Margin" user)
		(31 "F.CrtYd" user "Package Geometry/Place Bound Top")
		(29 "B.CrtYd" user "Package Geometry/Place Bound Bottom")
		(35 "F.Fab" user "Ref Des/Assembly Top")
		(33 "B.Fab" user "Ref Des/Assembly Bottom")
	)
	(footprint ""
		(layer "F.Cu")
		(at 65.3796 -13.8176 180)
		(property "Reference" "C1832"
			(at 0 0 180)
			(layer "F.SilkS")
			(hide yes)
			(effects
				(font
					(size 1.27 1.27)
				)
			)
		)
		(property "Value" ""
			(at 0 0 180)
			(layer "F.Fab")
			(effects
				(font
					(size 1.27 1.27)
				)
			)
		)
		(duplicate_pad_numbers_are_jumpers no)
		(fp_line
			(start 0.7874 0.4064)
			(end -0.7874 0.4064)
			(stroke
				(width 0.1524)
				(type default)
			)
			(layer "F.SilkS")
		)
		(fp_line
			(start 0.7874 -0.4064)
			(end 0.7874 0.4064)
			(stroke
				(width 0.1524)
				(type default)
			)
			(layer "F.SilkS")
		)
		(fp_line
			(start -0.7874 0.4064)
			(end -0.7874 -0.4064)
			(stroke
				(width 0.1524)
				(type default)
			)
			(layer "F.SilkS")
		)
		(fp_line
			(start -0.7874 -0.4064)
			(end 0.7874 -0.4064)
			(stroke
				(width 0.1524)
				(type default)
			)
			(layer "F.SilkS")
		)
		(fp_line
			(start 0.67945 0.3048)
			(end 0.120396 0.3048)
			(stroke
				(width 0.1)
				(type default)
			)
			(layer "F.Fab")
		)
		(fp_line
			(start 0.67945 -0.3048)
			(end 0.67945 0.3048)
			(stroke
				(width 0.1)
				(type default)
			)
			(layer "F.Fab")
		)
		(fp_line
			(start 0.12065 -0.2794)
			(end 0.12065 -0.3048)
			(stroke
				(width 0.1)
				(type default)
			)
			(layer "F.Fab")
		)
		(fp_line
			(start 0.12065 -0.3048)
			(end 0.67945 -0.3048)
			(stroke
				(width 0.1)
				(type default)
			)
			(layer "F.Fab")
		)
		(fp_line
			(start 0.120396 0.3048)
			(end 0.120396 0.2794)
			(stroke
				(width 0.1)
				(type default)
			)
			(layer "F.Fab")
		)
		(fp_line
			(start 0.120396 0.2794)
			(end -0.12065 0.2794)
			(stroke
				(width 0.1)
				(type default)
			)
			(layer "F.Fab")
		)
		(fp_line
			(start -0.12065 0.3048)
			(end -0.67945 0.3048)
			(stroke
				(width 0.1)
				(type default)
			)
			(layer "F.Fab")
		)
		(fp_line
			(start -0.12065 0.2794)
			(end -0.12065 0.3048)
			(stroke
				(width 0.1)
				(type default)
			)
			(layer "F.Fab")
		)
		(fp_line
			(start -0.12065 -0.2794)
			(end 0.12065 -0.2794)
			(stroke
				(width 0.1)
				(type default)
			)
			(layer "F.Fab")
		)
		(fp_line
			(start -0.12065 -0.305054)
			(end -0.12065 -0.2794)
			(stroke
				(width 0.1)
				(type default)
			)
			(layer "F.Fab")
		)
		(fp_line
			(start -0.67945 0.3048)
			(end -0.67945 -0.305054)
			(stroke
				(width 0.1)
				(type default)
			)
			(layer "F.Fab")
		)
		(fp_line
			(start -0.67945 -0.305054)
			(end -0.12065 -0.305054)
			(stroke
				(width 0.1)
				(type default)
			)
			(layer "F.Fab")
		)
		(pad "1" smd circle
			(at -0.40005 0 180)
			(size 0 0)
			(layers "F.Cu" "F.Mask" "F.Paste")
			(net "P12V_OCP_V3_2_R")
		)
		(pad "2" smd circle
			(at 0.40005 0 180)
			(size 0 0)
			(layers "F.Cu" "F.Mask" "F.Paste")
			(net "GND")
		)
	)
	(footprint ""
		(layer "F.Cu")
		(at 303.200308 -40.890698)
		(property "Reference" "R3667"
			(at 0 0 0)
			(layer "F.SilkS")
			(hide yes)
			(effects
				(font
					(size 1.27 1.27)
				)
			)
		)
		(property "Value" ""
			(at 0 0 0)
			(layer "F.Fab")
			(effects
				(font
					(size 1.27 1.27)
				)
			)
		)
		(duplicate_pad_numbers_are_jumpers no)
		(fp_line
			(start -0.7874 -0.4064)
			(end 0.7874 -0.4064)
			(stroke
				(width 0.1524)
				(type default)
			)
			(layer "F.SilkS")
		)
		(fp_line
			(start -0.7874 0.4064)
			(end -0.7874 -0.4064)
			(stroke
				(width 0.1524)
				(type default)
			)
			(layer "F.SilkS")
		)
		(fp_line
			(start 0.7874 -0.4064)
			(end 0.7874 0.4064)
			(stroke
				(width 0.1524)
				(type default)
			)
			(layer "F.SilkS")
		)
		(fp_line
			(start 0.7874 0.4064)
			(end -0.7874 0.4064)
			(stroke
				(width 0.1524)
				(type default)
			)
			(layer "F.SilkS")
		)
		(fp_line
			(start -0.67945 -0.305054)
			(end -0.12065 -0.305054)
			(stroke
				(width 0.1)
				(type default)
			)
			(layer "F.Fab")
		)
		(fp_line
			(start -0.67945 0.3048)
			(end -0.67945 -0.305054)
			(stroke
				(width 0.1)
				(type default)
			)
			(layer "F.Fab")
		)
		(fp_line
			(start -0.12065 -0.305054)
			(end -0.12065 -0.2794)
			(stroke
				(width 0.1)
				(type default)
			)
			(layer "F.Fab")
		)
		(fp_line
			(start -0.12065 -0.2794)
			(end 0.12065 -0.2794)
			(stroke
				(width 0.1)
				(type default)
			)
			(layer "F.Fab")
		)
		(fp_line
			(start -0.12065 0.2794)
			(end -0.12065 0.3048)
			(stroke
				(width 0.1)
				(type default)
			)
			(layer "F.Fab")
		)
		(fp_line
			(start -0.12065 0.3048)
			(end -0.67945 0.3048)
			(stroke
				(width 0.1)
				(type default)
			)
			(layer "F.Fab")
		)
		(fp_line
			(start 0.120396 0.2794)
			(end -0.12065 0.2794)
			(stroke
				(width 0.1)
				(type default)
			)
			(layer "F.Fab")
		)
		(fp_line
			(start 0.120396 0.3048)
			(end 0.120396 0.2794)
			(stroke
				(width 0.1)
				(type default)
			)
			(layer "F.Fab")
		)
		(fp_line
			(start 0.12065 -0.3048)
			(end 0.67945 -0.3048)
			(stroke
				(width 0.1)
				(type default)
			)
			(layer "F.Fab")
		)
		(fp_line
			(start 0.12065 -0.2794)
			(end 0.12065 -0.3048)
			(stroke
				(width 0.1)
				(type default)
			)
			(layer "F.Fab")
		)
		(fp_line
			(start 0.67945 -0.3048)
			(end 0.67945 0.3048)
			(stroke
				(width 0.1)
				(type default)
			)
			(layer "F.Fab")
		)
		(fp_line
			(start 0.67945 0.3048)
			(end 0.120396 0.3048)
			(stroke
				(width 0.1)
				(type default)
			)
			(layer "F.Fab")
		)
		(pad "1" smd circle
			(at -0.40005 0)
			(size 0 0)
			(layers "F.Cu" "F.Mask" "F.Paste")
			(net "P3V3_AUX")
		)
		(pad "2" smd circle
			(at 0.40005 0)
			(size 0 0)
			(layers "F.Cu" "F.Mask" "F.Paste")
			(net "ADC128_A1")
		)
	)
)
